(kicad_pcb
	(version 20260206)
	(generator "pcbnew")
	(generator_version "10.0")
	(general
		(thickness 1.6)
		(legacy_teardrops no)
	)
	(paper "A4")
	(title_block
		(title "03242023_DA0F0TMBIJ0_F0T_Motherboard_J_brd_V01_OCP.brd")
		(comment 1 "Grand Teton / footprints 2149-2155 of 6105")
	)
	(layers
		(0 "F.Cu" signal "TOP")
		(4 "In1.Cu" signal "GND")
		(6 "In2.Cu" signal "IN1")
		(8 "In3.Cu" signal "GND1")
		(10 "In4.Cu" signal "IN2")
		(12 "In5.Cu" signal "GND2")
		(14 "In6.Cu" signal "IN3")
		(16 "In7.Cu" signal "GND3")
		(18 "In8.Cu" signal "VCC")
		(20 "In9.Cu" signal "VCC1")
		(22 "In10.Cu" signal "GND4")
		(24 "In11.Cu" signal "IN4")
		(26 "In12.Cu" signal "GND5")
		(28 "In13.Cu" signal "IN5")
		(30 "In14.Cu" signal "GND6")
		(32 "In15.Cu" signal "IN6")
		(34 "In16.Cu" signal "GND7")
		(2 "B.Cu" signal "BOTTOM")
		(9 "F.Adhes" user "F.Adhesive")
		(11 "B.Adhes" user "B.Adhesive")
		(13 "F.Paste" user "Package Geometry/Pastemask Top")
		(15 "B.Paste" user "Package Geometry/Pastemask Bottom")
		(5 "F.SilkS" user "Ref Des/Silkscreen Top")
		(7 "B.SilkS" user "Ref Des/Silkscreen Bottom")
		(1 "F.Mask" user "Board Geometry/Soldermask Top")
		(3 "B.Mask" user "Board Geometry/Soldermask Bottom")
		(17 "Dwgs.User" user "User.Drawings")
		(19 "Cmts.User" user "User.Comments")
		(21 "Eco1.User" user "User.Eco1")
		(23 "Eco2.User" user "User.Eco2")
		(25 "Edge.Cuts" user "Board Geometry/Outline")
		(27 "Margin" user)
		(31 "F.CrtYd" user "Package Geometry/Place Bound Top")
		(29 "B.CrtYd" user "Package Geometry/Place Bound Bottom")
		(35 "F.Fab" user "Ref Des/Assembly Top")
		(33 "B.Fab" user "Ref Des/Assembly Bottom")
	)
	(footprint ""
		(layer "F.Cu")
		(at 152.32888 -45.938948 90)
		(property "Reference" "R3594"
			(at 0 0 90)
			(layer "F.SilkS")
			(hide yes)
			(effects
				(font
					(size 1.27 1.27)
				)
			)
		)
		(property "Value" ""
			(at 0 0 90)
			(layer "F.Fab")
			(effects
				(font
					(size 1.27 1.27)
				)
			)
		)
		(duplicate_pad_numbers_are_jumpers no)
		(fp_line
			(start 0.7874 -0.4064)
			(end 0.7874 0.4064)
			(stroke
				(width 0.1524)
				(type default)
			)
			(layer "F.SilkS")
		)
		(fp_line
			(start -0.7874 -0.4064)
			(end 0.7874 -0.4064)
			(stroke
				(width 0.1524)
				(type default)
			)
			(layer "F.SilkS")
		)
		(fp_line
			(start 0.7874 0.4064)
			(end -0.7874 0.4064)
			(stroke
				(width 0.1524)
				(type default)
			)
			(layer "F.SilkS")
		)
		(fp_line
			(start -0.7874 0.4064)
			(end -0.7874 -0.4064)
			(stroke
				(width 0.1524)
				(type default)
			)
			(layer "F.SilkS")
		)
		(fp_line
			(start -0.12065 -0.305054)
			(end -0.12065 -0.2794)
			(stroke
				(width 0.1)
				(type default)
			)
			(layer "F.Fab")
		)
		(fp_line
			(start -0.67945 -0.305054)
			(end -0.12065 -0.305054)
			(stroke
				(width 0.1)
				(type default)
			)
			(layer "F.Fab")
		)
		(fp_line
			(start 0.67945 -0.3048)
			(end 0.67945 0.3048)
			(stroke
				(width 0.1)
				(type default)
			)
			(layer "F.Fab")
		)
		(fp_line
			(start 0.12065 -0.3048)
			(end 0.67945 -0.3048)
			(stroke
				(width 0.1)
				(type default)
			)
			(layer "F.Fab")
		)
		(fp_line
			(start 0.12065 -0.2794)
			(end 0.12065 -0.3048)
			(stroke
				(width 0.1)
				(type default)
			)
			(layer "F.Fab")
		)
		(fp_line
			(start -0.12065 -0.2794)
			(end 0.12065 -0.2794)
			(stroke
				(width 0.1)
				(type default)
			)
			(layer "F.Fab")
		)
		(fp_line
			(start 0.120396 0.2794)
			(end -0.12065 0.2794)
			(stroke
				(width 0.1)
				(type default)
			)
			(layer "F.Fab")
		)
		(fp_line
			(start -0.12065 0.2794)
			(end -0.12065 0.3048)
			(stroke
				(width 0.1)
				(type default)
			)
			(layer "F.Fab")
		)
		(fp_line
			(start 0.67945 0.3048)
			(end 0.120396 0.3048)
			(stroke
				(width 0.1)
				(type default)
			)
			(layer "F.Fab")
		)
		(fp_line
			(start 0.120396 0.3048)
			(end 0.120396 0.2794)
			(stroke
				(width 0.1)
				(type default)
			)
			(layer "F.Fab")
		)
		(fp_line
			(start -0.12065 0.3048)
			(end -0.67945 0.3048)
			(stroke
				(width 0.1)
				(type default)
			)
			(layer "F.Fab")
		)
		(fp_line
			(start -0.67945 0.3048)
			(end -0.67945 -0.305054)
			(stroke
				(width 0.1)
				(type default)
			)
			(layer "F.Fab")
		)
		(pad "1" smd circle
			(at -0.40005 0 90)
			(size 0 0)
			(layers "F.Cu" "F.Mask" "F.Paste")
			(net "SMB_INA230_3V3AUX_SCL")
		)
		(pad "2" smd circle
			(at 0.40005 0 90)
			(size 0 0)
			(layers "F.Cu" "F.Mask" "F.Paste")
			(net "SMB_INA230_4_3V3AUX_SCL_R")
		)
	)
	(footprint ""
		(layer "F.Cu")
		(at 260.806692 -407.416 -90)
		(property "Reference" "PR2534"
			(at 0 0 270)
			(layer "F.SilkS")
			(hide yes)
			(effects
				(font
					(size 1.27 1.27)
				)
			)
		)
		(property "Value" ""
			(at 0 0 270)
			(layer "F.Fab")
			(effects
				(font
					(size 1.27 1.27)
				)
			)
		)
		(duplicate_pad_numbers_are_jumpers no)
		(fp_line
			(start -3.9878 3.5814)
			(end -3.9878 -3.5814)
			(stroke
				(width 0.1524)
				(type default)
			)
			(layer "F.SilkS")
		)
		(fp_line
			(start 3.9878 3.5814)
			(end -3.9878 3.5814)
			(stroke
				(width 0.1524)
				(type default)
			)
			(layer "F.SilkS")
		)
		(fp_line
			(start -3.9878 -3.5814)
			(end 3.9878 -3.5814)
			(stroke
				(width 0.1524)
				(type default)
			)
			(layer "F.SilkS")
		)
		(fp_line
			(start 3.9878 -3.5814)
			(end 3.9878 3.5814)
			(stroke
				(width 0.1524)
				(type default)
			)
			(layer "F.SilkS")
		)
		(fp_line
			(start -3.5306 3.353054)
			(end -3.5306 -3.353054)
			(stroke
				(width 0.1)
				(type default)
			)
			(layer "F.Fab")
		)
		(fp_line
			(start 3.5306 3.353054)
			(end -3.5306 3.353054)
			(stroke
				(width 0.1)
				(type default)
			)
			(layer "F.Fab")
		)
		(fp_line
			(start -3.5306 -3.353054)
			(end 3.5306 -3.353054)
			(stroke
				(width 0.1)
				(type default)
			)
			(layer "F.Fab")
		)
		(fp_line
			(start 3.5306 -3.353054)
			(end 3.5306 3.353054)
			(stroke
				(width 0.1)
				(type default)
			)
			(layer "F.Fab")
		)
		(pad "1A" smd rect
			(at -2.249932 0 90)
			(size 3.2004 6.858)
			(layers "F.Cu" "F.Mask" "F.Paste")
			(net "P12V_PSU")
		)
		(pad "1B" smd rect
			(at -0.776732 0 270)
			(size 0.254 0.508)
			(layers "F.Cu" "F.Mask" "F.Paste")
			(net "P12V_HSC_SENSE2_R4_P")
		)
		(pad "2A" smd rect
			(at 2.249932 0 90)
			(size 3.2004 6.858)
			(layers "F.Cu" "F.Mask" "F.Paste")
			(net "P12V_MAIN_R")
		)
		(pad "2B" smd rect
			(at 0.776732 0 270)
			(size 0.254 0.508)
			(layers "F.Cu" "F.Mask" "F.Paste")
			(net "P12V_HSC_SENSE2_R4_N")
		)
	)
	(footprint ""
		(layer "F.Cu")
		(at 116.561616 -252.956568 -90)
		(property "Reference" "C277"
			(at 0 0 270)
			(layer "F.SilkS")
			(hide yes)
			(effects
				(font
					(size 1.27 1.27)
				)
			)
		)
		(property "Value" ""
			(at 0 0 270)
			(layer "F.Fab")
			(effects
				(font
					(size 1.27 1.27)
				)
			)
		)
		(duplicate_pad_numbers_are_jumpers no)
		(fp_line
			(start -0.7874 0.4064)
			(end -0.7874 -0.4064)
			(stroke
				(width 0.1524)
				(type default)
			)
			(layer "F.SilkS")
		)
		(fp_line
			(start 0.7874 0.4064)
			(end -0.7874 0.4064)
			(stroke
				(width 0.1524)
				(type default)
			)
			(layer "F.SilkS")
		)
		(fp_line
			(start -0.7874 -0.4064)
			(end 0.7874 -0.4064)
			(stroke
				(width 0.1524)
				(type default)
			)
			(layer "F.SilkS")
		)
		(fp_line
			(start 0.7874 -0.4064)
			(end 0.7874 0.4064)
			(stroke
				(width 0.1524)
				(type default)
			)
			(layer "F.SilkS")
		)
		(fp_line
			(start -0.67945 0.3048)
			(end -0.67945 -0.305054)
			(stroke
				(width 0.1)
				(type default)
			)
			(layer "F.Fab")
		)
		(fp_line
			(start -0.12065 0.3048)
			(end -0.67945 0.3048)
			(stroke
				(width 0.1)
				(type default)
			)
			(layer "F.Fab")
		)
		(fp_line
			(start 0.120396 0.3048)
			(end 0.120396 0.2794)
			(stroke
				(width 0.1)
				(type default)
			)
			(layer "F.Fab")
		)
		(fp_line
			(start 0.67945 0.3048)
			(end 0.120396 0.3048)
			(stroke
				(width 0.1)
				(type default)
			)
			(layer "F.Fab")
		)
		(fp_line
			(start -0.12065 0.2794)
			(end -0.12065 0.3048)
			(stroke
				(width 0.1)
				(type default)
			)
			(layer "F.Fab")
		)
		(fp_line
			(start 0.120396 0.2794)
			(end -0.12065 0.2794)
			(stroke
				(width 0.1)
				(type default)
			)
			(layer "F.Fab")
		)
		(fp_line
			(start -0.12065 -0.2794)
			(end 0.12065 -0.2794)
			(stroke
				(width 0.1)
				(type default)
			)
			(layer "F.Fab")
		)
		(fp_line
			(start 0.12065 -0.2794)
			(end 0.12065 -0.3048)
			(stroke
				(width 0.1)
				(type default)
			)
			(layer "F.Fab")
		)
		(fp_line
			(start 0.12065 -0.3048)
			(end 0.67945 -0.3048)
			(stroke
				(width 0.1)
				(type default)
			)
			(layer "F.Fab")
		)
		(fp_line
			(start 0.67945 -0.3048)
			(end 0.67945 0.3048)
			(stroke
				(width 0.1)
				(type default)
			)
			(layer "F.Fab")
		)
		(fp_line
			(start -0.67945 -0.305054)
			(end -0.12065 -0.305054)
			(stroke
				(width 0.1)
				(type default)
			)
			(layer "F.Fab")
		)
		(fp_line
			(start -0.12065 -0.305054)
			(end -0.12065 -0.2794)
			(stroke
				(width 0.1)
				(type default)
			)
			(layer "F.Fab")
		)
		(pad "1" smd circle
			(at -0.40005 0 270)
			(size 0 0)
			(layers "F.Cu" "F.Mask" "F.Paste")
			(net "PVCCIN_CPU1")
		)
		(pad "2" smd circle
			(at 0.40005 0 270)
			(size 0 0)
			(layers "F.Cu" "F.Mask" "F.Paste")
			(net "GND")
		)
	)
	(footprint ""
		(layer "F.Cu")
		(at 123.741942 -16.90751 180)
		(property "Reference" "R4200"
			(at 0 0 180)
			(layer "F.SilkS")
			(hide yes)
			(effects
				(font
					(size 1.27 1.27)
				)
			)
		)
		(property "Value" ""
			(at 0 0 180)
			(layer "F.Fab")
			(effects
				(font
					(size 1.27 1.27)
				)
			)
		)
		(duplicate_pad_numbers_are_jumpers no)
		(fp_line
			(start 0.7874 0.4064)
			(end -0.7874 0.4064)
			(stroke
				(width 0.1524)
				(type default)
			)
			(layer "F.SilkS")
		)
		(fp_line
			(start 0.7874 -0.4064)
			(end 0.7874 0.4064)
			(stroke
				(width 0.1524)
				(type default)
			)
			(layer "F.SilkS")
		)
		(fp_line
			(start -0.7874 0.4064)
			(end -0.7874 -0.4064)
			(stroke
				(width 0.1524)
				(type default)
			)
			(layer "F.SilkS")
		)
		(fp_line
			(start -0.7874 -0.4064)
			(end 0.7874 -0.4064)
			(stroke
				(width 0.1524)
				(type default)
			)
			(layer "F.SilkS")
		)
		(fp_line
			(start 0.67945 0.3048)
			(end 0.120396 0.3048)
			(stroke
				(width 0.1)
				(type default)
			)
			(layer "F.Fab")
		)
		(fp_line
			(start 0.67945 -0.3048)
			(end 0.67945 0.3048)
			(stroke
				(width 0.1)
				(type default)
			)
			(layer "F.Fab")
		)
		(fp_line
			(start 0.12065 -0.2794)
			(end 0.12065 -0.3048)
			(stroke
				(width 0.1)
				(type default)
			)
			(layer "F.Fab")
		)
		(fp_line
			(start 0.12065 -0.3048)
			(end 0.67945 -0.3048)
			(stroke
				(width 0.1)
				(type default)
			)
			(layer "F.Fab")
		)
		(fp_line
			(start 0.120396 0.3048)
			(end 0.120396 0.2794)
			(stroke
				(width 0.1)
				(type default)
			)
			(layer "F.Fab")
		)
		(fp_line
			(start 0.120396 0.2794)
			(end -0.12065 0.2794)
			(stroke
				(width 0.1)
				(type default)
			)
			(layer "F.Fab")
		)
		(fp_line
			(start -0.12065 0.3048)
			(end -0.67945 0.3048)
			(stroke
				(width 0.1)
				(type default)
			)
			(layer "F.Fab")
		)
		(fp_line
			(start -0.12065 0.2794)
			(end -0.12065 0.3048)
			(stroke
				(width 0.1)
				(type default)
			)
			(layer "F.Fab")
		)
		(fp_line
			(start -0.12065 -0.2794)
			(end 0.12065 -0.2794)
			(stroke
				(width 0.1)
				(type default)
			)
			(layer "F.Fab")
		)
		(fp_line
			(start -0.12065 -0.305054)
			(end -0.12065 -0.2794)
			(stroke
				(width 0.1)
				(type default)
			)
			(layer "F.Fab")
		)
		(fp_line
			(start -0.67945 0.3048)
			(end -0.67945 -0.305054)
			(stroke
				(width 0.1)
				(type default)
			)
			(layer "F.Fab")
		)
		(fp_line
			(start -0.67945 -0.305054)
			(end -0.12065 -0.305054)
			(stroke
				(width 0.1)
				(type default)
			)
			(layer "F.Fab")
		)
		(pad "1" smd circle
			(at -0.40005 0 180)
			(size 0 0)
			(layers "F.Cu" "F.Mask" "F.Paste")
			(net "P3V3_AUX")
		)
		(pad "2" smd circle
			(at 0.40005 0 180)
			(size 0 0)
			(layers "F.Cu" "F.Mask" "F.Paste")
			(net "U273_3_ADD0")
		)
	)
	(footprint ""
		(layer "F.Cu")
		(at 369.292632 -396.249398)
		(property "Reference" "R2706"
			(at 0 0 0)
			(layer "F.SilkS")
			(hide yes)
			(effects
				(font
					(size 1.27 1.27)
				)
			)
		)
		(property "Value" ""
			(at 0 0 0)
			(layer "F.Fab")
			(effects
				(font
					(size 1.27 1.27)
				)
			)
		)
		(duplicate_pad_numbers_are_jumpers no)
		(fp_line
			(start -0.7874 -0.4064)
			(end 0.7874 -0.4064)
			(stroke
				(width 0.1524)
				(type default)
			)
			(layer "F.SilkS")
		)
		(fp_line
			(start -0.7874 0.4064)
			(end -0.7874 -0.4064)
			(stroke
				(width 0.1524)
				(type default)
			)
			(layer "F.SilkS")
		)
		(fp_line
			(start 0.7874 -0.4064)
			(end 0.7874 0.4064)
			(stroke
				(width 0.1524)
				(type default)
			)
			(layer "F.SilkS")
		)
		(fp_line
			(start 0.7874 0.4064)
			(end -0.7874 0.4064)
			(stroke
				(width 0.1524)
				(type default)
			)
			(layer "F.SilkS")
		)
		(fp_line
			(start -0.67945 -0.305054)
			(end -0.12065 -0.305054)
			(stroke
				(width 0.1)
				(type default)
			)
			(layer "F.Fab")
		)
		(fp_line
			(start -0.67945 0.3048)
			(end -0.67945 -0.305054)
			(stroke
				(width 0.1)
				(type default)
			)
			(layer "F.Fab")
		)
		(fp_line
			(start -0.12065 -0.305054)
			(end -0.12065 -0.2794)
			(stroke
				(width 0.1)
				(type default)
			)
			(layer "F.Fab")
		)
		(fp_line
			(start -0.12065 -0.2794)
			(end 0.12065 -0.2794)
			(stroke
				(width 0.1)
				(type default)
			)
			(layer "F.Fab")
		)
		(fp_line
			(start -0.12065 0.2794)
			(end -0.12065 0.3048)
			(stroke
				(width 0.1)
				(type default)
			)
			(layer "F.Fab")
		)
		(fp_line
			(start -0.12065 0.3048)
			(end -0.67945 0.3048)
			(stroke
				(width 0.1)
				(type default)
			)
			(layer "F.Fab")
		)
		(fp_line
			(start 0.120396 0.2794)
			(end -0.12065 0.2794)
			(stroke
				(width 0.1)
				(type default)
			)
			(layer "F.Fab")
		)
		(fp_line
			(start 0.120396 0.3048)
			(end 0.120396 0.2794)
			(stroke
				(width 0.1)
				(type default)
			)
			(layer "F.Fab")
		)
		(fp_line
			(start 0.12065 -0.3048)
			(end 0.67945 -0.3048)
			(stroke
				(width 0.1)
				(type default)
			)
			(layer "F.Fab")
		)
		(fp_line
			(start 0.12065 -0.2794)
			(end 0.12065 -0.3048)
			(stroke
				(width 0.1)
				(type default)
			)
			(layer "F.Fab")
		)
		(fp_line
			(start 0.67945 -0.3048)
			(end 0.67945 0.3048)
			(stroke
				(width 0.1)
				(type default)
			)
			(layer "F.Fab")
		)
		(fp_line
			(start 0.67945 0.3048)
			(end 0.120396 0.3048)
			(stroke
				(width 0.1)
				(type default)
			)
			(layer "F.Fab")
		)
		(pad "1" smd circle
			(at -0.40005 0)
			(size 0 0)
			(layers "F.Cu" "F.Mask" "F.Paste")
			(net "I3C_BMC_SWB_R_SDA")
		)
		(pad "2" smd circle
			(at 0.40005 0)
			(size 0 0)
			(layers "F.Cu" "F.Mask" "F.Paste")
			(net "I3C_BMC_SWB_BUF_R_SDA")
		)
	)
	(footprint ""
		(layer "F.Cu")
		(at 313.144408 -402.371052 -90)
		(property "Reference" "C1572"
			(at 0 0 270)
			(layer "F.SilkS")
			(hide yes)
			(effects
				(font
					(size 1.27 1.27)
				)
			)
		)
		(property "Value" ""
			(at 0 0 270)
			(layer "F.Fab")
			(effects
				(font
					(size 1.27 1.27)
				)
			)
		)
		(duplicate_pad_numbers_are_jumpers no)
		(fp_line
			(start -0.299974 0.150114)
			(end -0.299974 -0.150114)
			(stroke
				(width 0.1)
				(type default)
			)
			(layer "F.Fab")
		)
		(fp_line
			(start 0.299974 0.150114)
			(end -0.299974 0.150114)
			(stroke
				(width 0.1)
				(type default)
			)
			(layer "F.Fab")
		)
		(fp_line
			(start -0.299974 -0.150114)
			(end 0.299974 -0.150114)
			(stroke
				(width 0.1)
				(type default)
			)
			(layer "F.Fab")
		)
		(fp_line
			(start 0.299974 -0.150114)
			(end 0.299974 0.150114)
			(stroke
				(width 0.1)
				(type default)
			)
			(layer "F.Fab")
		)
		(pad "1" smd rect
			(at -0.2667 0 270)
			(size 0.3048 0.381)
			(layers "F.Cu" "F.Mask" "F.Paste")
			(net "P5E_CPU0_PE4_TX_C_DN<3>")
		)
		(pad "2" smd rect
			(at 0.2667 0 270)
			(size 0.3048 0.381)
			(layers "F.Cu" "F.Mask" "F.Paste")
			(net "P5E_CPU0_PE4_TX_DN<3>")
		)
	)
	(footprint ""
		(layer "F.Cu")
		(at 164.64788 -108.295948 180)
		(property "Reference" "R1547"
			(at 0 0 180)
			(layer "F.SilkS")
			(hide yes)
			(effects
				(font
					(size 1.27 1.27)
				)
			)
		)
		(property "Value" ""
			(at 0 0 180)
			(layer "F.Fab")
			(effects
				(font
					(size 1.27 1.27)
				)
			)
		)
		(duplicate_pad_numbers_are_jumpers no)
		(fp_line
			(start 0.7874 0.4064)
			(end -0.7874 0.4064)
			(stroke
				(width 0.1524)
				(type default)
			)
			(layer "F.SilkS")
		)
		(fp_line
			(start 0.7874 -0.4064)
			(end 0.7874 0.4064)
			(stroke
				(width 0.1524)
				(type default)
			)
			(layer "F.SilkS")
		)
		(fp_line
			(start -0.7874 0.4064)
			(end -0.7874 -0.4064)
			(stroke
				(width 0.1524)
				(type default)
			)
			(layer "F.SilkS")
		)
		(fp_line
			(start -0.7874 -0.4064)
			(end 0.7874 -0.4064)
			(stroke
				(width 0.1524)
				(type default)
			)
			(layer "F.SilkS")
		)
		(fp_line
			(start 0.67945 0.3048)
			(end 0.120396 0.3048)
			(stroke
				(width 0.1)
				(type default)
			)
			(layer "F.Fab")
		)
		(fp_line
			(start 0.67945 -0.3048)
			(end 0.67945 0.3048)
			(stroke
				(width 0.1)
				(type default)
			)
			(layer "F.Fab")
		)
		(fp_line
			(start 0.12065 -0.2794)
			(end 0.12065 -0.3048)
			(stroke
				(width 0.1)
				(type default)
			)
			(layer "F.Fab")
		)
		(fp_line
			(start 0.12065 -0.3048)
			(end 0.67945 -0.3048)
			(stroke
				(width 0.1)
				(type default)
			)
			(layer "F.Fab")
		)
		(fp_line
			(start 0.120396 0.3048)
			(end 0.120396 0.2794)
			(stroke
				(width 0.1)
				(type default)
			)
			(layer "F.Fab")
		)
		(fp_line
			(start 0.120396 0.2794)
			(end -0.12065 0.2794)
			(stroke
				(width 0.1)
				(type default)
			)
			(layer "F.Fab")
		)
		(fp_line
			(start -0.12065 0.3048)
			(end -0.67945 0.3048)
			(stroke
				(width 0.1)
				(type default)
			)
			(layer "F.Fab")
		)
		(fp_line
			(start -0.12065 0.2794)
			(end -0.12065 0.3048)
			(stroke
				(width 0.1)
				(type default)
			)
			(layer "F.Fab")
		)
		(fp_line
			(start -0.12065 -0.2794)
			(end 0.12065 -0.2794)
			(stroke
				(width 0.1)
				(type default)
			)
			(layer "F.Fab")
		)
		(fp_line
			(start -0.12065 -0.305054)
			(end -0.12065 -0.2794)
			(stroke
				(width 0.1)
				(type default)
			)
			(layer "F.Fab")
		)
		(fp_line
			(start -0.67945 0.3048)
			(end -0.67945 -0.305054)
			(stroke
				(width 0.1)
				(type default)
			)
			(layer "F.Fab")
		)
		(fp_line
			(start -0.67945 -0.305054)
			(end -0.12065 -0.305054)
			(stroke
				(width 0.1)
				(type default)
			)
			(layer "F.Fab")
		)
		(pad "1" smd circle
			(at -0.40005 0 180)
			(size 0 0)
			(layers "F.Cu" "F.Mask" "F.Paste")
			(net "FM_TPM_PRSNT_R_N")
		)
		(pad "2" smd circle
			(at 0.40005 0 180)
			(size 0 0)
			(layers "F.Cu" "F.Mask" "F.Paste")
			(net "FM_TPM_PRSNT_N")
		)
	)
)
